(kicad_pcb
	(version 20260206)
	(generator "pcbnew")
	(generator_version "10.0")
	(general
		(thickness 1.6)
		(legacy_teardrops no)
	)
	(paper "A4")
	(title_block
		(title "03242023_DA0F0TMBIJ0_F0T_Motherboard_J_brd_V01_OCP.brd")
		(comment 1 "Grand Teton / footprint 2539 of 6105 (J25), pads 1-112 of 291")
	)
	(layers
		(0 "F.Cu" signal "TOP")
		(4 "In1.Cu" signal "GND")
		(6 "In2.Cu" signal "IN1")
		(8 "In3.Cu" signal "GND1")
		(10 "In4.Cu" signal "IN2")
		(12 "In5.Cu" signal "GND2")
		(14 "In6.Cu" signal "IN3")
		(16 "In7.Cu" signal "GND3")
		(18 "In8.Cu" signal "VCC")
		(20 "In9.Cu" signal "VCC1")
		(22 "In10.Cu" signal "GND4")
		(24 "In11.Cu" signal "IN4")
		(26 "In12.Cu" signal "GND5")
		(28 "In13.Cu" signal "IN5")
		(30 "In14.Cu" signal "GND6")
		(32 "In15.Cu" signal "IN6")
		(34 "In16.Cu" signal "GND7")
		(2 "B.Cu" signal "BOTTOM")
		(9 "F.Adhes" user "F.Adhesive")
		(11 "B.Adhes" user "B.Adhesive")
		(13 "F.Paste" user "Package Geometry/Pastemask Top")
		(15 "B.Paste" user "Package Geometry/Pastemask Bottom")
		(5 "F.SilkS" user "Ref Des/Silkscreen Top")
		(7 "B.SilkS" user "Ref Des/Silkscreen Bottom")
		(1 "F.Mask" user "Board Geometry/Soldermask Top")
		(3 "B.Mask" user "Board Geometry/Soldermask Bottom")
		(17 "Dwgs.User" user "User.Drawings")
		(19 "Cmts.User" user "User.Comments")
		(21 "Eco1.User" user "User.Eco1")
		(23 "Eco2.User" user "User.Eco2")
		(25 "Edge.Cuts" user "Board Geometry/Outline")
		(27 "Margin" user)
		(31 "F.CrtYd" user "Package Geometry/Place Bound Top")
		(29 "B.CrtYd" user "Package Geometry/Place Bound Bottom")
		(35 "F.Fab" user "Ref Des/Assembly Top")
		(33 "B.Fab" user "Ref Des/Assembly Bottom")
	)
	(footprint ""
		(layer "F.Cu")
		(at 168.40708 -258.091686)
		(property "Reference" "J25"
			(at -3.683 -81.702148 0)
			(unlocked yes)
			(layer "F.SilkS")
			(effects
				(font
					(size 0.7874 0.5842)
					(thickness 0.1524)
				)
				(justify left)
			)
		)
		(property "Value" ""
			(at 0 0 0)
			(layer "F.Fab")
			(effects
				(font
					(size 1.27 1.27)
				)
			)
		)
		(duplicate_pad_numbers_are_jumpers no)
		(pad "1" smd rect
			(at -2.050034 -63.324994 270)
			(size 0.519938 1.4986)
			(layers "F.Cu" "F.Mask" "F.Paste")
			(net "P12V_S3_AUX_CPU1_NVDIMM")
		)
		(pad "2" smd rect
			(at -2.050034 -62.47511 270)
			(size 0.519938 1.4986)
			(layers "F.Cu" "F.Mask" "F.Paste")
			(net "TP_CHE_CPU1_DIMM1_FRU_0")
		)
		(pad "3" smd rect
			(at -2.050034 -61.624972 270)
			(size 0.519938 1.4986)
			(layers "F.Cu" "F.Mask" "F.Paste")
			(net "P3V3_AUX")
		)
		(pad "4" smd rect
			(at -2.050034 -60.775088 270)
			(size 0.519938 1.4986)
			(layers "F.Cu" "F.Mask" "F.Paste")
			(net "I3C_SPD_DDREFGH_CPU1_LVC1_SCL_R")
		)
		(pad "5" smd rect
			(at -2.050034 -59.92495 270)
			(size 0.519938 1.4986)
			(layers "F.Cu" "F.Mask" "F.Paste")
			(net "I3C_SPD_DDREFGH_CPU1_LVC1_SDA")
		)
		(pad "6" smd rect
			(at -2.050034 -59.075066 270)
			(size 0.519938 1.4986)
			(layers "F.Cu" "F.Mask" "F.Paste")
			(net "GND")
		)
		(pad "7" smd rect
			(at -2.050034 -58.224928 270)
			(size 0.519938 1.4986)
			(layers "F.Cu" "F.Mask" "F.Paste")
			(net "M_E_CPU1_SA_DQ<0>")
		)
		(pad "8" smd rect
			(at -2.050034 -57.375044 270)
			(size 0.519938 1.4986)
			(layers "F.Cu" "F.Mask" "F.Paste")
			(net "GND")
		)
		(pad "9" smd rect
			(at -2.050034 -56.524906 270)
			(size 0.519938 1.4986)
			(layers "F.Cu" "F.Mask" "F.Paste")
			(net "M_E_CPU1_SA_DQ<1>")
		)
		(pad "10" smd rect
			(at -2.050034 -55.675022 270)
			(size 0.519938 1.4986)
			(layers "F.Cu" "F.Mask" "F.Paste")
			(net "GND")
		)
		(pad "11" smd rect
			(at -2.050034 -54.824884 270)
			(size 0.519938 1.4986)
			(layers "F.Cu" "F.Mask" "F.Paste")
			(net "M_E_CPU1_SA_DQS_DP<0>")
		)
		(pad "12" smd rect
			(at -2.050034 -53.975 270)
			(size 0.519938 1.4986)
			(layers "F.Cu" "F.Mask" "F.Paste")
			(net "M_E_CPU1_SA_DQS_DN<0>")
		)
		(pad "13" smd rect
			(at -2.050034 -53.125116 270)
			(size 0.519938 1.4986)
			(layers "F.Cu" "F.Mask" "F.Paste")
			(net "GND")
		)
		(pad "14" smd rect
			(at -2.050034 -52.274978 270)
			(size 0.519938 1.4986)
			(layers "F.Cu" "F.Mask" "F.Paste")
			(net "M_E_CPU1_SA_DQ<4>")
		)
		(pad "15" smd rect
			(at -2.050034 -51.425094 270)
			(size 0.519938 1.4986)
			(layers "F.Cu" "F.Mask" "F.Paste")
			(net "GND")
		)
		(pad "16" smd rect
			(at -2.050034 -50.574956 270)
			(size 0.519938 1.4986)
			(layers "F.Cu" "F.Mask" "F.Paste")
			(net "M_E_CPU1_SA_DQ<5>")
		)
		(pad "17" smd rect
			(at -2.050034 -49.725072 270)
			(size 0.519938 1.4986)
			(layers "F.Cu" "F.Mask" "F.Paste")
			(net "GND")
		)
		(pad "18" smd rect
			(at -2.050034 -48.874934 270)
			(size 0.519938 1.4986)
			(layers "F.Cu" "F.Mask" "F.Paste")
			(net "M_E_CPU1_SA_DQ<8>")
		)
		(pad "19" smd rect
			(at -2.050034 -48.02505 270)
			(size 0.519938 1.4986)
			(layers "F.Cu" "F.Mask" "F.Paste")
			(net "GND")
		)
		(pad "20" smd rect
			(at -2.050034 -47.174912 270)
			(size 0.519938 1.4986)
			(layers "F.Cu" "F.Mask" "F.Paste")
			(net "M_E_CPU1_SA_DQ<9>")
		)
		(pad "21" smd rect
			(at -2.050034 -46.325028 270)
			(size 0.519938 1.4986)
			(layers "F.Cu" "F.Mask" "F.Paste")
			(net "GND")
		)
		(pad "22" smd rect
			(at -2.050034 -45.47489 270)
			(size 0.519938 1.4986)
			(layers "F.Cu" "F.Mask" "F.Paste")
			(net "M_E_CPU1_SA_DQS_DP<1>")
		)
		(pad "23" smd rect
			(at -2.050034 -44.625006 270)
			(size 0.519938 1.4986)
			(layers "F.Cu" "F.Mask" "F.Paste")
			(net "M_E_CPU1_SA_DQS_DN<1>")
		)
		(pad "24" smd rect
			(at -2.050034 -43.775122 270)
			(size 0.519938 1.4986)
			(layers "F.Cu" "F.Mask" "F.Paste")
			(net "GND")
		)
		(pad "25" smd rect
			(at -2.050034 -42.924984 270)
			(size 0.519938 1.4986)
			(layers "F.Cu" "F.Mask" "F.Paste")
			(net "M_E_CPU1_SA_DQ<12>")
		)
		(pad "26" smd rect
			(at -2.050034 -42.0751 270)
			(size 0.519938 1.4986)
			(layers "F.Cu" "F.Mask" "F.Paste")
			(net "GND")
		)
		(pad "27" smd rect
			(at -2.050034 -41.224962 270)
			(size 0.519938 1.4986)
			(layers "F.Cu" "F.Mask" "F.Paste")
			(net "M_E_CPU1_SA_DQ<13>")
		)
		(pad "28" smd rect
			(at -2.050034 -40.375078 270)
			(size 0.519938 1.4986)
			(layers "F.Cu" "F.Mask" "F.Paste")
			(net "GND")
		)
		(pad "29" smd rect
			(at -2.050034 -39.52494 270)
			(size 0.519938 1.4986)
			(layers "F.Cu" "F.Mask" "F.Paste")
			(net "M_E_CPU1_SA_DQ<16>")
		)
		(pad "30" smd rect
			(at -2.050034 -38.675056 270)
			(size 0.519938 1.4986)
			(layers "F.Cu" "F.Mask" "F.Paste")
			(net "GND")
		)
		(pad "31" smd rect
			(at -2.050034 -37.824918 270)
			(size 0.519938 1.4986)
			(layers "F.Cu" "F.Mask" "F.Paste")
			(net "M_E_CPU1_SA_DQ<17>")
		)
		(pad "32" smd rect
			(at -2.050034 -36.975034 270)
			(size 0.519938 1.4986)
			(layers "F.Cu" "F.Mask" "F.Paste")
			(net "GND")
		)
		(pad "33" smd rect
			(at -2.050034 -36.124896 270)
			(size 0.519938 1.4986)
			(layers "F.Cu" "F.Mask" "F.Paste")
			(net "M_E_CPU1_SA_DQS_DP<2>")
		)
		(pad "34" smd rect
			(at -2.050034 -35.275012 270)
			(size 0.519938 1.4986)
			(layers "F.Cu" "F.Mask" "F.Paste")
			(net "M_E_CPU1_SA_DQS_DN<2>")
		)
		(pad "35" smd rect
			(at -2.050034 -34.425128 270)
			(size 0.519938 1.4986)
			(layers "F.Cu" "F.Mask" "F.Paste")
			(net "GND")
		)
		(pad "36" smd rect
			(at -2.050034 -33.57499 270)
			(size 0.519938 1.4986)
			(layers "F.Cu" "F.Mask" "F.Paste")
			(net "M_E_CPU1_SA_DQ<20>")
		)
		(pad "37" smd rect
			(at -2.050034 -32.725106 270)
			(size 0.519938 1.4986)
			(layers "F.Cu" "F.Mask" "F.Paste")
			(net "GND")
		)
		(pad "38" smd rect
			(at -2.050034 -31.874968 270)
			(size 0.519938 1.4986)
			(layers "F.Cu" "F.Mask" "F.Paste")
			(net "M_E_CPU1_SA_DQ<21>")
		)
		(pad "39" smd rect
			(at -2.050034 -31.025084 270)
			(size 0.519938 1.4986)
			(layers "F.Cu" "F.Mask" "F.Paste")
			(net "GND")
		)
		(pad "40" smd rect
			(at -2.050034 -30.174946 270)
			(size 0.519938 1.4986)
			(layers "F.Cu" "F.Mask" "F.Paste")
			(net "M_E_CPU1_SA_DQ<24>")
		)
		(pad "41" smd rect
			(at -2.050034 -29.325062 270)
			(size 0.519938 1.4986)
			(layers "F.Cu" "F.Mask" "F.Paste")
			(net "GND")
		)
		(pad "42" smd rect
			(at -2.050034 -28.474924 270)
			(size 0.519938 1.4986)
			(layers "F.Cu" "F.Mask" "F.Paste")
			(net "M_E_CPU1_SA_DQ<25>")
		)
		(pad "43" smd rect
			(at -2.050034 -27.62504 270)
			(size 0.519938 1.4986)
			(layers "F.Cu" "F.Mask" "F.Paste")
			(net "GND")
		)
		(pad "44" smd rect
			(at -2.050034 -26.774902 270)
			(size 0.519938 1.4986)
			(layers "F.Cu" "F.Mask" "F.Paste")
			(net "M_E_CPU1_SA_DQS_DP<3>")
		)
		(pad "45" smd rect
			(at -2.050034 -25.925018 270)
			(size 0.519938 1.4986)
			(layers "F.Cu" "F.Mask" "F.Paste")
			(net "M_E_CPU1_SA_DQS_DN<3>")
		)
		(pad "46" smd rect
			(at -2.050034 -25.07488 270)
			(size 0.519938 1.4986)
			(layers "F.Cu" "F.Mask" "F.Paste")
			(net "GND")
		)
		(pad "47" smd rect
			(at -2.050034 -24.224996 270)
			(size 0.519938 1.4986)
			(layers "F.Cu" "F.Mask" "F.Paste")
			(net "M_E_CPU1_SA_DQ<28>")
		)
		(pad "48" smd rect
			(at -2.050034 -23.375112 270)
			(size 0.519938 1.4986)
			(layers "F.Cu" "F.Mask" "F.Paste")
			(net "GND")
		)
		(pad "49" smd rect
			(at -2.050034 -22.524974 270)
			(size 0.519938 1.4986)
			(layers "F.Cu" "F.Mask" "F.Paste")
			(net "M_E_CPU1_SA_DQ<29>")
		)
		(pad "50" smd rect
			(at -2.050034 -21.67509 270)
			(size 0.519938 1.4986)
			(layers "F.Cu" "F.Mask" "F.Paste")
			(net "GND")
		)
		(pad "51" smd rect
			(at -2.050034 -20.824952 270)
			(size 0.519938 1.4986)
			(layers "F.Cu" "F.Mask" "F.Paste")
			(net "M_E_CPU1_SA_CB<0>")
		)
		(pad "52" smd rect
			(at -2.050034 -19.975068 270)
			(size 0.519938 1.4986)
			(layers "F.Cu" "F.Mask" "F.Paste")
			(net "GND")
		)
		(pad "53" smd rect
			(at -2.050034 -19.12493 270)
			(size 0.519938 1.4986)
			(layers "F.Cu" "F.Mask" "F.Paste")
			(net "M_E_CPU1_SA_CB<1>")
		)
		(pad "54" smd rect
			(at -2.050034 -18.275046 270)
			(size 0.519938 1.4986)
			(layers "F.Cu" "F.Mask" "F.Paste")
			(net "GND")
		)
		(pad "55" smd rect
			(at -2.050034 -17.424908 270)
			(size 0.519938 1.4986)
			(layers "F.Cu" "F.Mask" "F.Paste")
			(net "M_E_CPU1_SA_DQS_DP<4>")
		)
		(pad "56" smd rect
			(at -2.050034 -16.575024 270)
			(size 0.519938 1.4986)
			(layers "F.Cu" "F.Mask" "F.Paste")
			(net "M_E_CPU1_SA_DQS_DN<4>")
		)
		(pad "57" smd rect
			(at -2.050034 -15.724886 270)
			(size 0.519938 1.4986)
			(layers "F.Cu" "F.Mask" "F.Paste")
			(net "GND")
		)
		(pad "58" smd rect
			(at -2.050034 -14.875002 270)
			(size 0.519938 1.4986)
			(layers "F.Cu" "F.Mask" "F.Paste")
			(net "M_E_CPU1_SA_CB<4>")
		)
		(pad "59" smd rect
			(at -2.050034 -14.025118 270)
			(size 0.519938 1.4986)
			(layers "F.Cu" "F.Mask" "F.Paste")
			(net "GND")
		)
		(pad "60" smd rect
			(at -2.050034 -13.17498 270)
			(size 0.519938 1.4986)
			(layers "F.Cu" "F.Mask" "F.Paste")
			(net "M_E_CPU1_SA_CB<5>")
		)
		(pad "61" smd rect
			(at -2.050034 -12.325096 270)
			(size 0.519938 1.4986)
			(layers "F.Cu" "F.Mask" "F.Paste")
			(net "GND")
		)
		(pad "62" smd rect
			(at -2.050034 -11.474958 270)
			(size 0.519938 1.4986)
			(layers "F.Cu" "F.Mask" "F.Paste")
			(net "M_E_CPU1_ALERT_N")
		)
		(pad "63" smd rect
			(at -2.050034 -10.625074 270)
			(size 0.519938 1.4986)
			(layers "F.Cu" "F.Mask" "F.Paste")
			(net "GND")
		)
		(pad "64" smd rect
			(at -2.050034 -9.774936 270)
			(size 0.519938 1.4986)
			(layers "F.Cu" "F.Mask" "F.Paste")
			(net "M_E_CPU1_SA_CS_N<0>")
		)
		(pad "65" smd rect
			(at -2.050034 -8.925052 270)
			(size 0.519938 1.4986)
			(layers "F.Cu" "F.Mask" "F.Paste")
			(net "GND")
		)
		(pad "66" smd rect
			(at -2.050034 -8.074914 270)
			(size 0.519938 1.4986)
			(layers "F.Cu" "F.Mask" "F.Paste")
			(net "M_E_CPU1_SA_CA<0>")
		)
		(pad "67" smd rect
			(at -2.050034 -7.22503 270)
			(size 0.519938 1.4986)
			(layers "F.Cu" "F.Mask" "F.Paste")
			(net "GND")
		)
		(pad "68" smd rect
			(at -2.050034 -6.374892 270)
			(size 0.519938 1.4986)
			(layers "F.Cu" "F.Mask" "F.Paste")
			(net "M_E_CPU1_SA_CA<2>")
		)
		(pad "69" smd rect
			(at -2.050034 -5.525008 270)
			(size 0.519938 1.4986)
			(layers "F.Cu" "F.Mask" "F.Paste")
			(net "GND")
		)
		(pad "70" smd rect
			(at -2.050034 -4.675124 270)
			(size 0.519938 1.4986)
			(layers "F.Cu" "F.Mask" "F.Paste")
			(net "M_E_CPU1_SA_CA<4>")
		)
		(pad "71" smd rect
			(at -2.050034 -3.824986 270)
			(size 0.519938 1.4986)
			(layers "F.Cu" "F.Mask" "F.Paste")
			(net "GND")
		)
		(pad "72" smd rect
			(at -2.050034 -2.975102 270)
			(size 0.519938 1.4986)
			(layers "F.Cu" "F.Mask" "F.Paste")
			(net "M_E_CPU1_SA_CA<6>")
		)
		(pad "73" smd rect
			(at -2.050034 -2.124964 270)
			(size 0.519938 1.4986)
			(layers "F.Cu" "F.Mask" "F.Paste")
			(net "GND")
		)
		(pad "74" smd rect
			(at -2.050034 -1.27508 270)
			(size 0.519938 1.4986)
			(layers "F.Cu" "F.Mask" "F.Paste")
			(net "M_E_CPU1_SA_PAR")
		)
		(pad "75" smd rect
			(at -2.050034 -0.424942 270)
			(size 0.519938 1.4986)
			(layers "F.Cu" "F.Mask" "F.Paste")
			(net "GND")
		)
		(pad "76" smd rect
			(at -2.050034 5.525008 270)
			(size 0.519938 1.4986)
			(layers "F.Cu" "F.Mask" "F.Paste")
			(net "M_E_CPU1_SB_CA<0>")
		)
		(pad "77" smd rect
			(at -2.050034 6.374892 270)
			(size 0.519938 1.4986)
			(layers "F.Cu" "F.Mask" "F.Paste")
			(net "GND")
		)
		(pad "78" smd rect
			(at -2.050034 7.22503 270)
			(size 0.519938 1.4986)
			(layers "F.Cu" "F.Mask" "F.Paste")
			(net "M_E_CPU1_SB_CA<2>")
		)
		(pad "79" smd rect
			(at -2.050034 8.074914 270)
			(size 0.519938 1.4986)
			(layers "F.Cu" "F.Mask" "F.Paste")
			(net "GND")
		)
		(pad "80" smd rect
			(at -2.050034 8.925052 270)
			(size 0.519938 1.4986)
			(layers "F.Cu" "F.Mask" "F.Paste")
			(net "M_E_CPU1_SB_CA<4>")
		)
		(pad "81" smd rect
			(at -2.050034 9.774936 270)
			(size 0.519938 1.4986)
			(layers "F.Cu" "F.Mask" "F.Paste")
			(net "GND")
		)
		(pad "82" smd rect
			(at -2.050034 10.625074 270)
			(size 0.519938 1.4986)
			(layers "F.Cu" "F.Mask" "F.Paste")
			(net "M_E_CPU1_SB_CA<6>")
		)
		(pad "83" smd rect
			(at -2.050034 11.474958 270)
			(size 0.519938 1.4986)
			(layers "F.Cu" "F.Mask" "F.Paste")
			(net "GND")
		)
		(pad "84" smd rect
			(at -2.050034 12.325096 270)
			(size 0.519938 1.4986)
			(layers "F.Cu" "F.Mask" "F.Paste")
			(net "M_E_CPU1_SB_CS_N<0>")
		)
		(pad "85" smd rect
			(at -2.050034 13.17498 270)
			(size 0.519938 1.4986)
			(layers "F.Cu" "F.Mask" "F.Paste")
			(net "GND")
		)
		(pad "86" smd rect
			(at -2.050034 14.025118 270)
			(size 0.519938 1.4986)
			(layers "F.Cu" "F.Mask" "F.Paste")
			(net "M_E_CPU1_SA_RSP<0>")
		)
		(pad "87" smd rect
			(at -2.050034 14.875002 270)
			(size 0.519938 1.4986)
			(layers "F.Cu" "F.Mask" "F.Paste")
			(net "M_E_CPU1_SB_RSP<0>")
		)
		(pad "88" smd rect
			(at -2.050034 15.724886 270)
			(size 0.519938 1.4986)
			(layers "F.Cu" "F.Mask" "F.Paste")
			(net "GND")
		)
		(pad "89" smd rect
			(at -2.050034 16.575024 270)
			(size 0.519938 1.4986)
			(layers "F.Cu" "F.Mask" "F.Paste")
			(net "M_E_CPU1_SB_CB<4>")
		)
		(pad "90" smd rect
			(at -2.050034 17.424908 270)
			(size 0.519938 1.4986)
			(layers "F.Cu" "F.Mask" "F.Paste")
			(net "GND")
		)
		(pad "91" smd rect
			(at -2.050034 18.275046 270)
			(size 0.519938 1.4986)
			(layers "F.Cu" "F.Mask" "F.Paste")
			(net "M_E_CPU1_SB_CB<5>")
		)
		(pad "92" smd rect
			(at -2.050034 19.12493 270)
			(size 0.519938 1.4986)
			(layers "F.Cu" "F.Mask" "F.Paste")
			(net "GND")
		)
		(pad "93" smd rect
			(at -2.050034 19.975068 270)
			(size 0.519938 1.4986)
			(layers "F.Cu" "F.Mask" "F.Paste")
			(net "M_E_CPU1_SB_DQS_DP<9>")
		)
		(pad "94" smd rect
			(at -2.050034 20.824952 270)
			(size 0.519938 1.4986)
			(layers "F.Cu" "F.Mask" "F.Paste")
			(net "M_E_CPU1_SB_DQS_DN<9>")
		)
		(pad "95" smd rect
			(at -2.050034 21.67509 270)
			(size 0.519938 1.4986)
			(layers "F.Cu" "F.Mask" "F.Paste")
			(net "GND")
		)
		(pad "96" smd rect
			(at -2.050034 22.524974 270)
			(size 0.519938 1.4986)
			(layers "F.Cu" "F.Mask" "F.Paste")
			(net "M_E_CPU1_SB_CB<0>")
		)
		(pad "97" smd rect
			(at -2.050034 23.375112 270)
			(size 0.519938 1.4986)
			(layers "F.Cu" "F.Mask" "F.Paste")
			(net "GND")
		)
		(pad "98" smd rect
			(at -2.050034 24.224996 270)
			(size 0.519938 1.4986)
			(layers "F.Cu" "F.Mask" "F.Paste")
			(net "M_E_CPU1_SB_CB<1>")
		)
		(pad "99" smd rect
			(at -2.050034 25.07488 270)
			(size 0.519938 1.4986)
			(layers "F.Cu" "F.Mask" "F.Paste")
			(net "GND")
		)
		(pad "100" smd rect
			(at -2.050034 25.925018 270)
			(size 0.519938 1.4986)
			(layers "F.Cu" "F.Mask" "F.Paste")
			(net "M_E_CPU1_SB_DQ<0>")
		)
		(pad "101" smd rect
			(at -2.050034 26.774902 270)
			(size 0.519938 1.4986)
			(layers "F.Cu" "F.Mask" "F.Paste")
			(net "GND")
		)
		(pad "102" smd rect
			(at -2.050034 27.62504 270)
			(size 0.519938 1.4986)
			(layers "F.Cu" "F.Mask" "F.Paste")
			(net "M_E_CPU1_SB_DQ<1>")
		)
		(pad "103" smd rect
			(at -2.050034 28.474924 270)
			(size 0.519938 1.4986)
			(layers "F.Cu" "F.Mask" "F.Paste")
			(net "GND")
		)
		(pad "104" smd rect
			(at -2.050034 29.325062 270)
			(size 0.519938 1.4986)
			(layers "F.Cu" "F.Mask" "F.Paste")
			(net "M_E_CPU1_SB_DQS_DP<0>")
		)
		(pad "105" smd rect
			(at -2.050034 30.174946 270)
			(size 0.519938 1.4986)
			(layers "F.Cu" "F.Mask" "F.Paste")
			(net "M_E_CPU1_SB_DQS_DN<0>")
		)
		(pad "106" smd rect
			(at -2.050034 31.025084 270)
			(size 0.519938 1.4986)
			(layers "F.Cu" "F.Mask" "F.Paste")
			(net "GND")
		)
		(pad "107" smd rect
			(at -2.050034 31.874968 270)
			(size 0.519938 1.4986)
			(layers "F.Cu" "F.Mask" "F.Paste")
			(net "M_E_CPU1_SB_DQ<4>")
		)
		(pad "108" smd rect
			(at -2.050034 32.725106 270)
			(size 0.519938 1.4986)
			(layers "F.Cu" "F.Mask" "F.Paste")
			(net "GND")
		)
		(pad "109" smd rect
			(at -2.050034 33.57499 270)
			(size 0.519938 1.4986)
			(layers "F.Cu" "F.Mask" "F.Paste")
			(net "M_E_CPU1_SB_DQ<5>")
		)
		(pad "110" smd rect
			(at -2.050034 34.425128 270)
			(size 0.519938 1.4986)
			(layers "F.Cu" "F.Mask" "F.Paste")
			(net "GND")
		)
		(pad "111" smd rect
			(at -2.050034 35.275012 270)
			(size 0.519938 1.4986)
			(layers "F.Cu" "F.Mask" "F.Paste")
			(net "M_E_CPU1_SB_DQ<8>")
		)
		(pad "112" smd rect
			(at -2.050034 36.124896 270)
			(size 0.519938 1.4986)
			(layers "F.Cu" "F.Mask" "F.Paste")
			(net "GND")
		)
	)
)
